(kicad_pcb
	(version 20260206)
	(generator "pcbnew")
	(generator_version "10.0")
	(general
		(thickness 1.6)
		(legacy_teardrops no)
	)
	(paper "A4")
	(title_block
		(title "01162023_DA0F0TEBIF0_F0T_Expander_BD_F_brd_V02_OCP.brd")
		(comment 1 "Grand Teton / footprint 6619 of 9728 (PEX0), pads 234-355 of 2397")
	)
	(layers
		(0 "F.Cu" signal "TOP")
		(4 "In1.Cu" signal "GND")
		(6 "In2.Cu" signal "VCC")
		(8 "In3.Cu" signal "VCC1")
		(10 "In4.Cu" signal "GND1")
		(12 "In5.Cu" signal "IN1")
		(14 "In6.Cu" signal "GND2")
		(16 "In7.Cu" signal "IN2")
		(18 "In8.Cu" signal "GND3")
		(20 "In9.Cu" signal "IN3")
		(22 "In10.Cu" signal "GND4")
		(24 "In11.Cu" signal "IN4")
		(26 "In12.Cu" signal "GND5")
		(28 "In13.Cu" signal "IN5")
		(30 "In14.Cu" signal "GND6")
		(32 "In15.Cu" signal "IN6")
		(34 "In16.Cu" signal "GND7")
		(2 "B.Cu" signal "BOTTOM")
		(9 "F.Adhes" user "F.Adhesive")
		(11 "B.Adhes" user "B.Adhesive")
		(13 "F.Paste" user "Package Geometry/Pastemask Top")
		(15 "B.Paste" user "Package Geometry/Pastemask Bottom")
		(5 "F.SilkS" user "Ref Des/Silkscreen Top")
		(7 "B.SilkS" user "Ref Des/Silkscreen Bottom")
		(1 "F.Mask" user "Board Geometry/Soldermask Top")
		(3 "B.Mask" user "Board Geometry/Soldermask Bottom")
		(17 "Dwgs.User" user "User.Drawings")
		(19 "Cmts.User" user "User.Comments")
		(21 "Eco1.User" user "User.Eco1")
		(23 "Eco2.User" user "User.Eco2")
		(25 "Edge.Cuts" user "Board Geometry/Outline")
		(27 "Margin" user)
		(31 "F.CrtYd" user "Package Geometry/Place Bound Top")
		(29 "B.CrtYd" user "Package Geometry/Place Bound Bottom")
		(35 "F.Fab" user "Ref Des/Assembly Top")
		(33 "B.Fab" user "Ref Des/Assembly Bottom")
	)
	(footprint ""
		(layer "F.Cu")
		(at 59.649868 -295.89984)
		(property "Reference" "PEX0"
			(at -3.360166 35.566858 0)
			(unlocked yes)
			(layer "F.SilkS")
			(effects
				(font
					(size 2.032 1.524)
					(thickness 0.1524)
				)
				(justify left)
			)
		)
		(property "Value" ""
			(at 0 0 0)
			(layer "F.Fab")
			(effects
				(font
					(size 1.27 1.27)
				)
			)
		)
		(duplicate_pad_numbers_are_jumpers no)
		(pad "AD40" smd circle
			(at 14.249908 -0.94996)
			(size 0.4572 0.4572)
			(layers "F.Cu" "F.Mask" "F.Paste")
			(net "GND")
		)
		(pad "AD41" smd circle
			(at 15.200122 -0.94996)
			(size 0.4572 0.4572)
			(layers "F.Cu" "F.Mask" "F.Paste")
			(net "Net_2821")
		)
		(pad "AD42" smd circle
			(at 16.150082 -0.94996)
			(size 0.4572 0.4572)
			(layers "F.Cu" "F.Mask" "F.Paste")
			(net "Net_2805")
		)
		(pad "AD43" smd circle
			(at 17.100042 -0.94996)
			(size 0.4572 0.4572)
			(layers "F.Cu" "F.Mask" "F.Paste")
			(net "GND")
		)
		(pad "AD44" smd circle
			(at 18.050002 -0.94996)
			(size 0.4572 0.4572)
			(layers "F.Cu" "F.Mask" "F.Paste")
			(net "GND")
		)
		(pad "AD45" smd circle
			(at 18.999962 -0.94996)
			(size 0.4572 0.4572)
			(layers "F.Cu" "F.Mask" "F.Paste")
			(net "GND")
		)
		(pad "AD46" smd circle
			(at 19.949922 -0.94996)
			(size 0.4572 0.4572)
			(layers "F.Cu" "F.Mask" "F.Paste")
			(net "GND")
		)
		(pad "AD47" smd circle
			(at 20.899882 -0.94996)
			(size 0.4572 0.4572)
			(layers "F.Cu" "F.Mask" "F.Paste")
			(net "GND")
		)
		(pad "AD48" smd circle
			(at 21.850096 -0.94996)
			(size 0.4572 0.4572)
			(layers "F.Cu" "F.Mask" "F.Paste")
			(net "Net_2789")
		)
		(pad "AD49" smd circle
			(at 22.800056 -0.94996)
			(size 0.4572 0.4572)
			(layers "F.Cu" "F.Mask" "F.Paste")
			(net "Net_2773")
		)
		(pad "AE1" smd circle
			(at -22.800056 0)
			(size 0.4572 0.4572)
			(layers "F.Cu" "F.Mask" "F.Paste")
			(net "CLK_100M_DB800ZL_PEX0_S3_R_DN")
		)
		(pad "AE2" smd circle
			(at -21.850096 0)
			(size 0.4572 0.4572)
			(layers "F.Cu" "F.Mask" "F.Paste")
			(net "CLK_100M_DB800ZL_PEX0_S3_R_DP")
		)
		(pad "AE3" smd circle
			(at -20.899882 0)
			(size 0.4572 0.4572)
			(layers "F.Cu" "F.Mask" "F.Paste")
			(net "GND")
		)
		(pad "AE4" smd circle
			(at -19.949922 0)
			(size 0.4572 0.4572)
			(layers "F.Cu" "F.Mask" "F.Paste")
			(net "GND")
		)
		(pad "AE5" smd circle
			(at -18.999962 0)
			(size 0.4572 0.4572)
			(layers "F.Cu" "F.Mask" "F.Paste")
			(net "GND")
		)
		(pad "AE6" smd circle
			(at -18.050002 0)
			(size 0.4572 0.4572)
			(layers "F.Cu" "F.Mask" "F.Paste")
			(net "GND")
		)
		(pad "AE7" smd circle
			(at -17.100042 0)
			(size 0.4572 0.4572)
			(layers "F.Cu" "F.Mask" "F.Paste")
			(net "Net_2912")
		)
		(pad "AE8" smd circle
			(at -16.150082 0)
			(size 0.4572 0.4572)
			(layers "F.Cu" "F.Mask" "F.Paste")
			(net "Net_2919")
		)
		(pad "AE9" smd circle
			(at -15.200122 0)
			(size 0.4572 0.4572)
			(layers "F.Cu" "F.Mask" "F.Paste")
			(net "GND")
		)
		(pad "AE10" smd circle
			(at -14.249908 0)
			(size 0.4572 0.4572)
			(layers "F.Cu" "F.Mask" "F.Paste")
			(net "P1V8_PEX")
		)
		(pad "AE11" smd circle
			(at -13.299948 0)
			(size 0.4572 0.4572)
			(layers "F.Cu" "F.Mask" "F.Paste")
			(net "GND")
		)
		(pad "AE12" smd circle
			(at -12.349988 0)
			(size 0.4572 0.4572)
			(layers "F.Cu" "F.Mask" "F.Paste")
			(net "GND")
		)
		(pad "AE13" smd circle
			(at -11.400028 0)
			(size 0.4572 0.4572)
			(layers "F.Cu" "F.Mask" "F.Paste")
			(net "PCEPLL3_VDDA18_PEX0")
		)
		(pad "AE14" smd circle
			(at -10.450068 0)
			(size 0.4572 0.4572)
			(layers "F.Cu" "F.Mask" "F.Paste")
			(net "GND")
		)
		(pad "AE15" smd circle
			(at -9.500108 0)
			(size 0.4572 0.4572)
			(layers "F.Cu" "F.Mask" "F.Paste")
			(net "P0V8_PEX0")
		)
		(pad "AE16" smd circle
			(at -8.549894 0)
			(size 0.4572 0.4572)
			(layers "F.Cu" "F.Mask" "F.Paste")
			(net "GND")
		)
		(pad "AE17" smd circle
			(at -7.599934 0)
			(size 0.4572 0.4572)
			(layers "F.Cu" "F.Mask" "F.Paste")
			(net "P0V8_PEX0")
		)
		(pad "AE18" smd circle
			(at -6.649974 0)
			(size 0.4572 0.4572)
			(layers "F.Cu" "F.Mask" "F.Paste")
			(net "GND")
		)
		(pad "AE19" smd circle
			(at -5.700014 0)
			(size 0.4572 0.4572)
			(layers "F.Cu" "F.Mask" "F.Paste")
			(net "P0V8_PEX0")
		)
		(pad "AE20" smd circle
			(at -4.750054 0)
			(size 0.4572 0.4572)
			(layers "F.Cu" "F.Mask" "F.Paste")
			(net "GND")
		)
		(pad "AE21" smd circle
			(at -3.800094 0)
			(size 0.4572 0.4572)
			(layers "F.Cu" "F.Mask" "F.Paste")
			(net "P0V8_PEX0")
		)
		(pad "AE22" smd circle
			(at -2.84988 0)
			(size 0.4572 0.4572)
			(layers "F.Cu" "F.Mask" "F.Paste")
			(net "GND")
		)
		(pad "AE23" smd circle
			(at -1.89992 0)
			(size 0.4572 0.4572)
			(layers "F.Cu" "F.Mask" "F.Paste")
			(net "P0V8_PEX0")
		)
		(pad "AE24" smd circle
			(at -0.94996 0)
			(size 0.4572 0.4572)
			(layers "F.Cu" "F.Mask" "F.Paste")
			(net "GND")
		)
		(pad "AE25" smd circle
			(at 0 0)
			(size 0.4572 0.4572)
			(layers "F.Cu" "F.Mask" "F.Paste")
			(net "P0V8_PEX0")
		)
		(pad "AE26" smd circle
			(at 0.94996 0)
			(size 0.4572 0.4572)
			(layers "F.Cu" "F.Mask" "F.Paste")
			(net "GND")
		)
		(pad "AE27" smd circle
			(at 1.89992 0)
			(size 0.4572 0.4572)
			(layers "F.Cu" "F.Mask" "F.Paste")
			(net "P0V8_PEX0")
		)
		(pad "AE28" smd circle
			(at 2.84988 0)
			(size 0.4572 0.4572)
			(layers "F.Cu" "F.Mask" "F.Paste")
			(net "GND")
		)
		(pad "AE29" smd circle
			(at 3.800094 0)
			(size 0.4572 0.4572)
			(layers "F.Cu" "F.Mask" "F.Paste")
			(net "P0V8_PEX0")
		)
		(pad "AE30" smd circle
			(at 4.750054 0)
			(size 0.4572 0.4572)
			(layers "F.Cu" "F.Mask" "F.Paste")
			(net "GND")
		)
		(pad "AE31" smd circle
			(at 5.700014 0)
			(size 0.4572 0.4572)
			(layers "F.Cu" "F.Mask" "F.Paste")
			(net "P0V8_PEX0")
		)
		(pad "AE32" smd circle
			(at 6.649974 0)
			(size 0.4572 0.4572)
			(layers "F.Cu" "F.Mask" "F.Paste")
			(net "GND")
		)
		(pad "AE33" smd circle
			(at 7.599934 0)
			(size 0.4572 0.4572)
			(layers "F.Cu" "F.Mask" "F.Paste")
			(net "P0V8_SERDES_VDDA_PEX0")
		)
		(pad "AE34" smd circle
			(at 8.549894 0)
			(size 0.4572 0.4572)
			(layers "F.Cu" "F.Mask" "F.Paste")
			(net "P0V8_SERDES_VDDA_PEX0")
		)
		(pad "AE35" smd circle
			(at 9.500108 0)
			(size 0.4572 0.4572)
			(layers "F.Cu" "F.Mask" "F.Paste")
			(net "GND")
		)
		(pad "AE36" smd circle
			(at 10.450068 0)
			(size 0.4572 0.4572)
			(layers "F.Cu" "F.Mask" "F.Paste")
			(net "P1V25_PEX0")
		)
		(pad "AE37" smd circle
			(at 11.400028 0)
			(size 0.4572 0.4572)
			(layers "F.Cu" "F.Mask" "F.Paste")
			(net "GND")
		)
		(pad "AE38" smd circle
			(at 12.349988 0)
			(size 0.4572 0.4572)
			(layers "F.Cu" "F.Mask" "F.Paste")
			(net "P1V25_SERDES_VDDPLL_PEX0")
		)
		(pad "AE39" smd circle
			(at 13.299948 0)
			(size 0.4572 0.4572)
			(layers "F.Cu" "F.Mask" "F.Paste")
			(net "GND")
		)
		(pad "AE40" smd circle
			(at 14.249908 0)
			(size 0.4572 0.4572)
			(layers "F.Cu" "F.Mask" "F.Paste")
			(net "GND")
		)
		(pad "AE41" smd circle
			(at 15.200122 0)
			(size 0.4572 0.4572)
			(layers "F.Cu" "F.Mask" "F.Paste")
			(net "GND")
		)
		(pad "AE42" smd circle
			(at 16.150082 0)
			(size 0.4572 0.4572)
			(layers "F.Cu" "F.Mask" "F.Paste")
			(net "GND")
		)
		(pad "AE43" smd circle
			(at 17.100042 0)
			(size 0.4572 0.4572)
			(layers "F.Cu" "F.Mask" "F.Paste")
			(net "Net_2822")
		)
		(pad "AE44" smd circle
			(at 18.050002 0)
			(size 0.4572 0.4572)
			(layers "F.Cu" "F.Mask" "F.Paste")
			(net "Net_2806")
		)
		(pad "AE45" smd circle
			(at 18.999962 0)
			(size 0.4572 0.4572)
			(layers "F.Cu" "F.Mask" "F.Paste")
			(net "GND")
		)
		(pad "AE46" smd circle
			(at 19.949922 0)
			(size 0.4572 0.4572)
			(layers "F.Cu" "F.Mask" "F.Paste")
			(net "Net_2790")
		)
		(pad "AE47" smd circle
			(at 20.899882 0)
			(size 0.4572 0.4572)
			(layers "F.Cu" "F.Mask" "F.Paste")
			(net "Net_2774")
		)
		(pad "AE48" smd circle
			(at 21.850096 0)
			(size 0.4572 0.4572)
			(layers "F.Cu" "F.Mask" "F.Paste")
			(net "GND")
		)
		(pad "AE49" smd circle
			(at 22.800056 0)
			(size 0.4572 0.4572)
			(layers "F.Cu" "F.Mask" "F.Paste")
			(net "GND")
		)
		(pad "AF1" smd circle
			(at -22.800056 0.94996)
			(size 0.4572 0.4572)
			(layers "F.Cu" "F.Mask" "F.Paste")
			(net "GND")
		)
		(pad "AF2" smd circle
			(at -21.850096 0.94996)
			(size 0.4572 0.4572)
			(layers "F.Cu" "F.Mask" "F.Paste")
			(net "GND")
		)
		(pad "AF3" smd circle
			(at -20.899882 0.94996)
			(size 0.4572 0.4572)
			(layers "F.Cu" "F.Mask" "F.Paste")
			(net "GND")
		)
		(pad "AF4" smd circle
			(at -19.949922 0.94996)
			(size 0.4572 0.4572)
			(layers "F.Cu" "F.Mask" "F.Paste")
			(net "Net_2831")
		)
		(pad "AF5" smd circle
			(at -18.999962 0.94996)
			(size 0.4572 0.4572)
			(layers "F.Cu" "F.Mask" "F.Paste")
			(net "Net_2832")
		)
		(pad "AF6" smd circle
			(at -18.050002 0.94996)
			(size 0.4572 0.4572)
			(layers "F.Cu" "F.Mask" "F.Paste")
			(net "GND")
		)
		(pad "AF7" smd circle
			(at -17.100042 0.94996)
			(size 0.4572 0.4572)
			(layers "F.Cu" "F.Mask" "F.Paste")
			(net "SPI_PEX0_SDIO0")
		)
		(pad "AF8" smd circle
			(at -16.150082 0.94996)
			(size 0.4572 0.4572)
			(layers "F.Cu" "F.Mask" "F.Paste")
			(net "SPI_PEX0_SDIO1")
		)
		(pad "AF9" smd circle
			(at -15.200122 0.94996)
			(size 0.4572 0.4572)
			(layers "F.Cu" "F.Mask" "F.Paste")
			(net "GND")
		)
		(pad "AF10" smd circle
			(at -14.249908 0.94996)
			(size 0.4572 0.4572)
			(layers "F.Cu" "F.Mask" "F.Paste")
			(net "P1V8_PEX")
		)
		(pad "AF11" smd circle
			(at -13.299948 0.94996)
			(size 0.4572 0.4572)
			(layers "F.Cu" "F.Mask" "F.Paste")
			(net "GND")
		)
		(pad "AF12" smd circle
			(at -12.349988 0.94996)
			(size 0.4572 0.4572)
			(layers "F.Cu" "F.Mask" "F.Paste")
			(net "PCEPLL4_VDDA18_PEX0")
		)
		(pad "AF13" smd circle
			(at -11.400028 0.94996)
			(size 0.4572 0.4572)
			(layers "F.Cu" "F.Mask" "F.Paste")
			(net "GND")
		)
		(pad "AF14" smd circle
			(at -10.450068 0.94996)
			(size 0.4572 0.4572)
			(layers "F.Cu" "F.Mask" "F.Paste")
			(net "P0V8_PEX0")
		)
		(pad "AF15" smd circle
			(at -9.500108 0.94996)
			(size 0.4572 0.4572)
			(layers "F.Cu" "F.Mask" "F.Paste")
			(net "GND")
		)
		(pad "AF16" smd circle
			(at -8.549894 0.94996)
			(size 0.4572 0.4572)
			(layers "F.Cu" "F.Mask" "F.Paste")
			(net "P0V8_PEX0")
		)
		(pad "AF17" smd circle
			(at -7.599934 0.94996)
			(size 0.4572 0.4572)
			(layers "F.Cu" "F.Mask" "F.Paste")
			(net "GND")
		)
		(pad "AF18" smd circle
			(at -6.649974 0.94996)
			(size 0.4572 0.4572)
			(layers "F.Cu" "F.Mask" "F.Paste")
			(net "P0V8_PEX0")
		)
		(pad "AF19" smd circle
			(at -5.700014 0.94996)
			(size 0.4572 0.4572)
			(layers "F.Cu" "F.Mask" "F.Paste")
			(net "GND")
		)
		(pad "AF20" smd circle
			(at -4.750054 0.94996)
			(size 0.4572 0.4572)
			(layers "F.Cu" "F.Mask" "F.Paste")
			(net "P0V8_PEX0")
		)
		(pad "AF21" smd circle
			(at -3.800094 0.94996)
			(size 0.4572 0.4572)
			(layers "F.Cu" "F.Mask" "F.Paste")
			(net "GND")
		)
		(pad "AF22" smd circle
			(at -2.84988 0.94996)
			(size 0.4572 0.4572)
			(layers "F.Cu" "F.Mask" "F.Paste")
			(net "P0V8_PEX0")
		)
		(pad "AF23" smd circle
			(at -1.89992 0.94996)
			(size 0.4572 0.4572)
			(layers "F.Cu" "F.Mask" "F.Paste")
			(net "GND")
		)
		(pad "AF24" smd circle
			(at -0.94996 0.94996)
			(size 0.4572 0.4572)
			(layers "F.Cu" "F.Mask" "F.Paste")
			(net "P0V8_PEX0")
		)
		(pad "AF25" smd circle
			(at 0 0.94996)
			(size 0.4572 0.4572)
			(layers "F.Cu" "F.Mask" "F.Paste")
			(net "GND")
		)
		(pad "AF26" smd circle
			(at 0.94996 0.94996)
			(size 0.4572 0.4572)
			(layers "F.Cu" "F.Mask" "F.Paste")
			(net "P0V8_PEX0")
		)
		(pad "AF27" smd circle
			(at 1.89992 0.94996)
			(size 0.4572 0.4572)
			(layers "F.Cu" "F.Mask" "F.Paste")
			(net "GND")
		)
		(pad "AF28" smd circle
			(at 2.84988 0.94996)
			(size 0.4572 0.4572)
			(layers "F.Cu" "F.Mask" "F.Paste")
			(net "P0V8_PEX0")
		)
		(pad "AF29" smd circle
			(at 3.800094 0.94996)
			(size 0.4572 0.4572)
			(layers "F.Cu" "F.Mask" "F.Paste")
			(net "GND")
		)
		(pad "AF30" smd circle
			(at 4.750054 0.94996)
			(size 0.4572 0.4572)
			(layers "F.Cu" "F.Mask" "F.Paste")
			(net "P0V8_PEX0")
		)
		(pad "AF31" smd circle
			(at 5.700014 0.94996)
			(size 0.4572 0.4572)
			(layers "F.Cu" "F.Mask" "F.Paste")
			(net "GND")
		)
		(pad "AF32" smd circle
			(at 6.649974 0.94996)
			(size 0.4572 0.4572)
			(layers "F.Cu" "F.Mask" "F.Paste")
			(net "P0V8_SERDES_VDDA_PEX0")
		)
		(pad "AF33" smd circle
			(at 7.599934 0.94996)
			(size 0.4572 0.4572)
			(layers "F.Cu" "F.Mask" "F.Paste")
			(net "P0V8_SERDES_VDDA_PEX0")
		)
		(pad "AF34" smd circle
			(at 8.549894 0.94996)
			(size 0.4572 0.4572)
			(layers "F.Cu" "F.Mask" "F.Paste")
			(net "P0V8_SERDES_VDDA_PEX0")
		)
		(pad "AF35" smd circle
			(at 9.500108 0.94996)
			(size 0.4572 0.4572)
			(layers "F.Cu" "F.Mask" "F.Paste")
			(net "GND")
		)
		(pad "AF36" smd circle
			(at 10.450068 0.94996)
			(size 0.4572 0.4572)
			(layers "F.Cu" "F.Mask" "F.Paste")
			(net "P1V25_PEX0")
		)
		(pad "AF37" smd circle
			(at 11.400028 0.94996)
			(size 0.4572 0.4572)
			(layers "F.Cu" "F.Mask" "F.Paste")
			(net "GND")
		)
		(pad "AF38" smd circle
			(at 12.349988 0.94996)
			(size 0.4572 0.4572)
			(layers "F.Cu" "F.Mask" "F.Paste")
			(net "P1V25_SERDES_VDDPLL_PEX0")
		)
		(pad "AF39" smd circle
			(at 13.299948 0.94996)
			(size 0.4572 0.4572)
			(layers "F.Cu" "F.Mask" "F.Paste")
			(net "GND")
		)
		(pad "AF40" smd circle
			(at 14.249908 0.94996)
			(size 0.4572 0.4572)
			(layers "F.Cu" "F.Mask" "F.Paste")
			(net "GND")
		)
		(pad "AF41" smd circle
			(at 15.200122 0.94996)
			(size 0.4572 0.4572)
			(layers "F.Cu" "F.Mask" "F.Paste")
			(net "Net_2823")
		)
		(pad "AF42" smd circle
			(at 16.150082 0.94996)
			(size 0.4572 0.4572)
			(layers "F.Cu" "F.Mask" "F.Paste")
			(net "Net_2807")
		)
		(pad "AF43" smd circle
			(at 17.100042 0.94996)
			(size 0.4572 0.4572)
			(layers "F.Cu" "F.Mask" "F.Paste")
			(net "GND")
		)
		(pad "AF44" smd circle
			(at 18.050002 0.94996)
			(size 0.4572 0.4572)
			(layers "F.Cu" "F.Mask" "F.Paste")
			(net "GND")
		)
		(pad "AF45" smd circle
			(at 18.999962 0.94996)
			(size 0.4572 0.4572)
			(layers "F.Cu" "F.Mask" "F.Paste")
			(net "GND")
		)
		(pad "AF46" smd circle
			(at 19.949922 0.94996)
			(size 0.4572 0.4572)
			(layers "F.Cu" "F.Mask" "F.Paste")
			(net "GND")
		)
		(pad "AF47" smd circle
			(at 20.899882 0.94996)
			(size 0.4572 0.4572)
			(layers "F.Cu" "F.Mask" "F.Paste")
			(net "GND")
		)
		(pad "AF48" smd circle
			(at 21.850096 0.94996)
			(size 0.4572 0.4572)
			(layers "F.Cu" "F.Mask" "F.Paste")
			(net "Net_2791")
		)
		(pad "AF49" smd circle
			(at 22.800056 0.94996)
			(size 0.4572 0.4572)
			(layers "F.Cu" "F.Mask" "F.Paste")
			(net "Net_2775")
		)
		(pad "AG1" smd circle
			(at -22.800056 1.89992)
			(size 0.4572 0.4572)
			(layers "F.Cu" "F.Mask" "F.Paste")
			(net "Net_2834")
		)
		(pad "AG2" smd circle
			(at -21.850096 1.89992)
			(size 0.4572 0.4572)
			(layers "F.Cu" "F.Mask" "F.Paste")
			(net "Net_2835")
		)
		(pad "AG3" smd circle
			(at -20.899882 1.89992)
			(size 0.4572 0.4572)
			(layers "F.Cu" "F.Mask" "F.Paste")
			(net "GND")
		)
		(pad "AG4" smd circle
			(at -19.949922 1.89992)
			(size 0.4572 0.4572)
			(layers "F.Cu" "F.Mask" "F.Paste")
			(net "GND")
		)
		(pad "AG5" smd circle
			(at -18.999962 1.89992)
			(size 0.4572 0.4572)
			(layers "F.Cu" "F.Mask" "F.Paste")
			(net "GND")
		)
		(pad "AG6" smd circle
			(at -18.050002 1.89992)
			(size 0.4572 0.4572)
			(layers "F.Cu" "F.Mask" "F.Paste")
			(net "GND")
		)
		(pad "AG7" smd circle
			(at -17.100042 1.89992)
			(size 0.4572 0.4572)
			(layers "F.Cu" "F.Mask" "F.Paste")
			(net "SPI_PEX0_RST_N")
		)
		(pad "AG8" smd circle
			(at -16.150082 1.89992)
			(size 0.4572 0.4572)
			(layers "F.Cu" "F.Mask" "F.Paste")
			(net "SPI_PEX0_SDIO2")
		)
		(pad "AG9" smd circle
			(at -15.200122 1.89992)
			(size 0.4572 0.4572)
			(layers "F.Cu" "F.Mask" "F.Paste")
			(net "GND")
		)
		(pad "AG10" smd circle
			(at -14.249908 1.89992)
			(size 0.4572 0.4572)
			(layers "F.Cu" "F.Mask" "F.Paste")
			(net "GND")
		)
		(pad "AG11" smd circle
			(at -13.299948 1.89992)
			(size 0.4572 0.4572)
			(layers "F.Cu" "F.Mask" "F.Paste")
			(net "GND")
		)
		(pad "AG12" smd circle
			(at -12.349988 1.89992)
			(size 0.4572 0.4572)
			(layers "F.Cu" "F.Mask" "F.Paste")
			(net "GND")
		)
		(pad "AG13" smd circle
			(at -11.400028 1.89992)
			(size 0.4572 0.4572)
			(layers "F.Cu" "F.Mask" "F.Paste")
			(net "PCEPLL5_VDDA18_PEX0")
		)
		(pad "AG14" smd circle
			(at -10.450068 1.89992)
			(size 0.4572 0.4572)
			(layers "F.Cu" "F.Mask" "F.Paste")
			(net "GND")
		)
	)
)
